# S9S_MB_2U (Grand Teton) — schematic netlist excerpt (pin names and nets, part order shuffled) for the footprints in the layout excerpt that follows; sources: Cadence DE-HDL packaged netlist, KiCad conversion of 03242023_DA0F0TMBIJ0_F0T_Motherboard_J_brd_V01_OCP.brd

C947  Q_CAP_DIFFBUS  DIFF BUS_0.22UF 6.3V 20% X6S  pkg C0201  page 173 : \1\ = P5E_CPU0_PE2_TX_C_DP<9> ; \2\ = P5E_CPU0_PE2_TX_DP<9>
R1694  Q_RES  10K 1% CHIP  pkg 0402LF  page 244 : A = P3V3_AUX ; B = PWRGD_DSW_PWROK

(kicad_pcb
	(version 20260206)
	(generator "pcbnew")
	(generator_version "10.0")
	(general
		(thickness 1.6)
		(legacy_teardrops no)
	)
	(paper "A4")
	(title_block
		(title "03242023_DA0F0TMBIJ0_F0T_Motherboard_J_brd_V01_OCP.brd")
		(comment 1 "Grand Teton / footprints 3092-3093 of 6105")
	)
	(layers
		(0 "F.Cu" signal "TOP")
		(4 "In1.Cu" signal "GND")
		(6 "In2.Cu" signal "IN1")
		(8 "In3.Cu" signal "GND1")
		(10 "In4.Cu" signal "IN2")
		(12 "In5.Cu" signal "GND2")
		(14 "In6.Cu" signal "IN3")
		(16 "In7.Cu" signal "GND3")
		(18 "In8.Cu" signal "VCC")
		(20 "In9.Cu" signal "VCC1")
		(22 "In10.Cu" signal "GND4")
		(24 "In11.Cu" signal "IN4")
		(26 "In12.Cu" signal "GND5")
		(28 "In13.Cu" signal "IN5")
		(30 "In14.Cu" signal "GND6")
		(32 "In15.Cu" signal "IN6")
		(34 "In16.Cu" signal "GND7")
		(2 "B.Cu" signal "BOTTOM")
		(9 "F.Adhes" user "F.Adhesive")
		(11 "B.Adhes" user "B.Adhesive")
		(13 "F.Paste" user "Package Geometry/Pastemask Top")
		(15 "B.Paste" user "Package Geometry/Pastemask Bottom")
		(5 "F.SilkS" user "Ref Des/Silkscreen Top")
		(7 "B.SilkS" user "Ref Des/Silkscreen Bottom")
		(1 "F.Mask" user "Board Geometry/Soldermask Top")
		(3 "B.Mask" user "Board Geometry/Soldermask Bottom")
		(17 "Dwgs.User" user "User.Drawings")
		(19 "Cmts.User" user "User.Comments")
		(21 "Eco1.User" user "User.Eco1")
		(23 "Eco2.User" user "User.Eco2")
		(25 "Edge.Cuts" user "Board Geometry/Outline")
		(27 "Margin" user)
		(31 "F.CrtYd" user "Package Geometry/Place Bound Top")
		(29 "B.CrtYd" user "Package Geometry/Place Bound Bottom")
		(35 "F.Fab" user "Ref Des/Assembly Top")
		(33 "B.Fab" user "Ref Des/Assembly Bottom")
	)
	(footprint ""
		(layer "F.Cu")
		(at 321.899788 -26.711656 90)
		(property "Reference" "R1694"
			(at 0 0 90)
			(layer "F.SilkS")
			(hide yes)
			(effects
				(font
					(size 1.27 1.27)
				)
			)
		)
		(property "Value" ""
			(at 0 0 90)
			(layer "F.Fab")
			(effects
				(font
					(size 1.27 1.27)
				)
			)
		)
		(duplicate_pad_numbers_are_jumpers no)
		(fp_line
			(start 0.7874 -0.4064)
			(end 0.7874 0.4064)
			(stroke
				(width 0.1524)
				(type default)
			)
			(layer "F.SilkS")
		)
		(fp_line
			(start -0.7874 -0.4064)
			(end 0.7874 -0.4064)
			(stroke
				(width 0.1524)
				(type default)
			)
			(layer "F.SilkS")
		)
		(fp_line
			(start 0.7874 0.4064)
			(end -0.7874 0.4064)
			(stroke
				(width 0.1524)
				(type default)
			)
			(layer "F.SilkS")
		)
		(fp_line
			(start -0.7874 0.4064)
			(end -0.7874 -0.4064)
			(stroke
				(width 0.1524)
				(type default)
			)
			(layer "F.SilkS")
		)
		(fp_line
			(start -0.12065 -0.305054)
			(end -0.12065 -0.2794)
			(stroke
				(width 0.1)
				(type default)
			)
			(layer "F.Fab")
		)
		(fp_line
			(start -0.67945 -0.305054)
			(end -0.12065 -0.305054)
			(stroke
				(width 0.1)
				(type default)
			)
			(layer "F.Fab")
		)
		(fp_line
			(start 0.67945 -0.3048)
			(end 0.67945 0.3048)
			(stroke
				(width 0.1)
				(type default)
			)
			(layer "F.Fab")
		)
		(fp_line
			(start 0.12065 -0.3048)
			(end 0.67945 -0.3048)
			(stroke
				(width 0.1)
				(type default)
			)
			(layer "F.Fab")
		)
		(fp_line
			(start 0.12065 -0.2794)
			(end 0.12065 -0.3048)
			(stroke
				(width 0.1)
				(type default)
			)
			(layer "F.Fab")
		)
		(fp_line
			(start -0.12065 -0.2794)
			(end 0.12065 -0.2794)
			(stroke
				(width 0.1)
				(type default)
			)
			(layer "F.Fab")
		)
		(fp_line
			(start 0.120396 0.2794)
			(end -0.12065 0.2794)
			(stroke
				(width 0.1)
				(type default)
			)
			(layer "F.Fab")
		)
		(fp_line
			(start -0.12065 0.2794)
			(end -0.12065 0.3048)
			(stroke
				(width 0.1)
				(type default)
			)
			(layer "F.Fab")
		)
		(fp_line
			(start 0.67945 0.3048)
			(end 0.120396 0.3048)
			(stroke
				(width 0.1)
				(type default)
			)
			(layer "F.Fab")
		)
		(fp_line
			(start 0.120396 0.3048)
			(end 0.120396 0.2794)
			(stroke
				(width 0.1)
				(type default)
			)
			(layer "F.Fab")
		)
		(fp_line
			(start -0.12065 0.3048)
			(end -0.67945 0.3048)
			(stroke
				(width 0.1)
				(type default)
			)
			(layer "F.Fab")
		)
		(fp_line
			(start -0.67945 0.3048)
			(end -0.67945 -0.305054)
			(stroke
				(width 0.1)
				(type default)
			)
			(layer "F.Fab")
		)
		(pad "1" smd circle
			(at -0.40005 0 90)
			(size 0 0)
			(layers "F.Cu" "F.Mask" "F.Paste")
			(net "P3V3_AUX")
		)
		(pad "2" smd circle
			(at 0.40005 0 90)
			(size 0 0)
			(layers "F.Cu" "F.Mask" "F.Paste")
			(net "PWRGD_DSW_PWROK")
		)
	)
	(footprint ""
		(layer "F.Cu")
		(at 389.77697 -402.371052 -90)
		(property "Reference" "C947"
			(at 0 0 270)
			(layer "F.SilkS")
			(hide yes)
			(effects
				(font
					(size 1.27 1.27)
				)
			)
		)
		(property "Value" ""
			(at 0 0 270)
			(layer "F.Fab")
			(effects
				(font
					(size 1.27 1.27)
				)
			)
		)
		(duplicate_pad_numbers_are_jumpers no)
		(fp_line
			(start -0.299974 0.150114)
			(end -0.299974 -0.150114)
			(stroke
				(width 0.1)
				(type default)
			)
			(layer "F.Fab")
		)
		(fp_line
			(start 0.299974 0.150114)
			(end -0.299974 0.150114)
			(stroke
				(width 0.1)
				(type default)
			)
			(layer "F.Fab")
		)
		(fp_line
			(start -0.299974 -0.150114)
			(end 0.299974 -0.150114)
			(stroke
				(width 0.1)
				(type default)
			)
			(layer "F.Fab")
		)
		(fp_line
			(start 0.299974 -0.150114)
			(end 0.299974 0.150114)
			(stroke
				(width 0.1)
				(type default)
			)
			(layer "F.Fab")
		)
		(pad "1" smd rect
			(at -0.2667 0 270)
			(size 0.3048 0.381)
			(layers "F.Cu" "F.Mask" "F.Paste")
			(net "P5E_CPU0_PE2_TX_C_DP<9>")
		)
		(pad "2" smd rect
			(at 0.2667 0 270)
			(size 0.3048 0.381)
			(layers "F.Cu" "F.Mask" "F.Paste")
			(net "P5E_CPU0_PE2_TX_DP<9>")
		)
	)
)
